# BASEBOARD_FAB2 (Tioga Pass) — schematic netlist excerpt (pin names and nets, part order shuffled) for the footprints in the layout excerpt that follows; sources: Cadence DE-HDL packaged netlist, KiCad conversion of Wiwynn_Tioga_Pass_MB.brd

J1A2  SCONN288_H44441004  SCONN  pkg PIP  page 85
  \12v\(1)  = P12V_NVDIMM_KLM
  VSS(93)  = GND
  DQ(4)  = M_L_DQ<5>
  VSS(92)  = GND
  DQ(0)  = M_L_DQ<1>
  VSS(91)  = GND
  DQS9P  = M_L_DQS_DP<9>
  DQS9N  = M_L_DQS_DN<9>
  VSS(90)  = GND
  DQ(6)  = M_L_DQ<7>
  VSS(89)  = GND
  DQ(2)  = M_L_DQ<3>
  VSS(88)  = GND
  DQ(12)  = M_L_DQ<13>
  VSS(87)  = GND
  DQ(8)  = M_L_DQ<9>
  VSS(86)  = GND
  DQS10P  = M_L_DQS_DP<10>
  DQS10N  = M_L_DQS_DN<10>
  VSS(85)  = GND
  DQ(14)  = M_L_DQ<15>
  VSS(84)  = GND
  DQ(10)  = M_L_DQ<11>
  VSS(83)  = GND
  DQ(20)  = M_L_DQ<21>
  VSS(82)  = GND
  DQ(16)  = M_L_DQ<17>
  VSS(81)  = GND
  DQS11P  = M_L_DQS_DP<11>
  DQS11N  = M_L_DQS_DN<11>
  VSS(80)  = GND
  DQ(22)  = M_L_DQ<23>
  VSS(79)  = GND
  DQ(18)  = M_L_DQ<19>
  VSS(78)  = GND
  DQ(28)  = M_L_DQ<29>
  VSS(77)  = GND
  DQ(24)  = M_L_DQ<25>
  VSS(76)  = GND
  DQS12P  = M_L_DQS_DP<12>
  DQS12N  = M_L_DQS_DN<12>
  VSS(75)  = GND
  DQ(30)  = M_L_DQ<31>
  VSS(74)  = GND
  DQ(26)  = M_L_DQ<27>
  VSS(73)  = GND
  CB(4)  = M_L_ECC<5>
  VSS(72)  = GND
  CB(0)  = M_L_ECC<1>
  VSS(71)  = GND
  DQS17P  = M_L_DQS_DP<17>
  DQS17N  = M_L_DQS_DN<17>
  VSS(70)  = GND
  CB(6)  = M_L_ECC<7>
  VSS(69)  = GND
  CB(2)  = M_L_ECC<3>
  VSS(68)  = GND
  RESET_N  = M_KLM_RST_N
  VDD(25)  = PVDDQ_KLM
  CKE(0)  = M_L_CKE<0>
  VDD(24)  = PVDDQ_KLM
  ACT_N  = M_L_ACT_N
  BG(0)  = M_L_BG<0>
  VDD(23)  = PVDDQ_KLM
  A12  = M_L_MA<12>
  A9  = M_L_MA<9>
  VDD(22)  = PVDDQ_KLM
  A8  = M_L_MA<8>
  A6  = M_L_MA<6>
  VDD(21)  = PVDDQ_KLM
  A3  = M_L_MA<3>
  A1  = M_L_MA<1>
  VDD(20)  = PVDDQ_KLM
  CK0P  = M_L_CLK_DP<0>
  CK0N  = M_L_CLK_DN<0>
  VDD(19)  = PVDDQ_KLM
  VTT(1)  = PVTT_KLM
  EVENT_N  = FM_DIMM_EVENT_COD_N
  A0  = M_L_MA<0>
  VDD(18)  = PVDDQ_KLM
  BA(0)  = M_L_BA<0>
  A16_RAS_N  = M_L_MA<16>
  VDD(17)  = PVDDQ_KLM
  S0_N  = M_L_CS_N<0>
  VDD(16)  = PVDDQ_KLM
  A15_CAS_N  = M_L_MA<15>
  ODT(0)  = M_L_ODT<0>
  VDD(15)  = PVDDQ_KLM
  S1_N  = M_L_CS_N<1>
  VDD(14)  = PVDDQ_KLM
  ODT(1)  = M_L_ODT<1>
  VDD(13)  = PVDDQ_KLM
  S2_N_C(0)  = M_L_CS_N<2>
  VSS(67)  = GND
  DQ(36)  = M_L_DQ<37>
  VSS(66)  = GND
  DQ(32)  = M_L_DQ<33>
  VSS(65)  = GND
  DQS13P  = M_L_DQS_DP<13>
  DQS13N  = M_L_DQS_DN<13>
  VSS(64)  = GND
  DQ(38)  = M_L_DQ<39>
  VSS(63)  = GND
  DQ(34)  = M_L_DQ<35>
  VSS(62)  = GND
  DQ(44)  = M_L_DQ<45>
  VSS(61)  = GND
  DQ(40)  = M_L_DQ<41>
  VSS(60)  = GND
  DQS14P  = M_L_DQS_DP<14>
  DQS14N  = M_L_DQS_DN<14>
  VSS(59)  = GND
  DQ(46)  = M_L_DQ<47>
  VSS(58)  = GND
  DQ(42)  = M_L_DQ<43>
  VSS(57)  = GND
  DQ(52)  = M_L_DQ<53>
  VSS(56)  = GND
  DQ(48)  = M_L_DQ<49>
  VSS(55)  = GND
  DQS15P  = M_L_DQS_DP<15>
  DQS15N  = M_L_DQS_DN<15>
  VSS(54)  = GND
  DQ(54)  = M_L_DQ<55>
  VSS(53)  = GND
  DQ(50)  = M_L_DQ<51>
  VSS(52)  = GND
  DQ(60)  = M_L_DQ<61>
  VSS(51)  = GND
  DQ(56)  = M_L_DQ<57>
  VSS(50)  = GND
  DQS16P  = M_L_DQS_DP<16>
  DQS16N  = M_L_DQS_DN<16>
  VSS(49)  = GND
  DQ(62)  = M_L_DQ<63>
  VSS(48)  = GND
  DQ(58)  = M_L_DQ<59>
  VSS(47)  = GND
  SA(0)  = GND
  SA(1)  = PVPP_KLM
  SCL  = SMB_DDR_KLM_VPP_SCL
  VPP(4)  = PVPP_KLM
  VPP(3)  = PVPP_KLM
  RFU(2)  = TP_CH_L_DIMM_L0_RFU_2
  \12v\(0)  = P12V_NVDIMM_KLM
  VREFCA  = M_L_VREF
  VSS(46)  = GND
  DQ(5)  = M_L_DQ<4>
  VSS(45)  = GND
  DQ(1)  = M_L_DQ<0>
  VSS(44)  = GND
  DQS0N  = M_L_DQS_DN<0>
  DQS0P  = M_L_DQS_DP<0>
  VSS(43)  = GND
  DQ(7)  = M_L_DQ<6>
  VSS(42)  = GND
  DQ(3)  = M_L_DQ<2>
  VSS(41)  = GND
  DQ(13)  = M_L_DQ<12>
  VSS(40)  = GND
  DQ(9)  = M_L_DQ<8>
  VSS(39)  = GND
  DQS1N  = M_L_DQS_DN<1>
  DQS1P  = M_L_DQS_DP<1>
  VSS(38)  = GND
  DQ(15)  = M_L_DQ<14>
  VSS(37)  = GND
  DQ(11)  = M_L_DQ<10>
  VSS(36)  = GND
  DQ(21)  = M_L_DQ<20>
  VSS(35)  = GND
  DQ(17)  = M_L_DQ<16>
  VSS(34)  = GND
  DQS2N  = M_L_DQS_DN<2>
  DQS2P  = M_L_DQS_DP<2>
  VSS(33)  = GND
  DQ(23)  = M_L_DQ<22>
  VSS(32)  = GND
  DQ(19)  = M_L_DQ<18>
  VSS(31)  = GND
  DQ(29)  = M_L_DQ<28>
  VSS(30)  = GND
  DQ(25)  = M_L_DQ<24>
  VSS(29)  = GND
  DQS3N  = M_L_DQS_DN<3>
  DQS3P  = M_L_DQS_DP<3>
  VSS(28)  = GND
  DQ(31)  = M_L_DQ<30>
  VSS(27)  = GND
  DQ(27)  = M_L_DQ<26>
  VSS(26)  = GND
  CB(5)  = M_L_ECC<4>
  VSS(25)  = GND
  CB(1)  = M_L_ECC<0>
  VSS(24)  = GND
  DQS8N  = M_L_DQS_DN<8>
  DQS8P  = M_L_DQS_DP<8>
  VSS(23)  = GND
  CB(7)  = M_L_ECC<6>
  VSS(22)  = GND
  CB(3)  = M_L_ECC<2>
  VSS(21)  = GND
  CKE(1)  = M_L_CKE<1>
  VDD(12)  = PVDDQ_KLM
  RFU(0)  = TP_CH_L_DIMM_L0_RFU_0
  VDD(11)  = PVDDQ_KLM
  BG(1)  = M_L_BG<1>
  ALERT_N  = M_L_ALERT_N
  VDD(10)  = PVDDQ_KLM
  A11  = M_L_MA<11>
  A7  = M_L_MA<7>
  VDD(9)  = PVDDQ_KLM
  A5  = M_L_MA<5>
  A4  = M_L_MA<4>
  VDD(8)  = PVDDQ_KLM
  A2  = M_L_MA<2>
  VDD(7)  = PVDDQ_KLM
  CK1P  = M_L_CLK_DP<1>
  CK1N  = M_L_CLK_DN<1>
  VDD(6)  = PVDDQ_KLM
  VTT(0)  = PVTT_KLM
  PAR  = M_L_PAR
  VDD(5)  = PVDDQ_KLM
  BA(1)  = M_L_BA<1>
  A10  = M_L_MA<10>
  VDD(4)  = PVDDQ_KLM
  RFU(1)  = TP_CH_L_DIMM_L0_RFU_1
  A14_WE_N  = M_L_MA<14>
  VDD(3)  = PVDDQ_KLM
  SAVE_N_NC  = FM_ADR_COMPLETE_KLM_N
  VDD(2)  = PVDDQ_KLM
  A13  = M_L_MA<13>
  VDD(1)  = PVDDQ_KLM
  A17  = M_L_MA<17>
  C(2)  = M_L_C<2>
  VDD(0)  = PVDDQ_KLM
  S3_N_C(1)  = M_L_CS_N<3>
  SA(2)  = GND
  VSS(20)  = GND
  DQ(37)  = M_L_DQ<36>
  VSS(19)  = GND
  DQ(33)  = M_L_DQ<32>
  VSS(18)  = GND
  DQS4N  = M_L_DQS_DN<4>
  DQS4P  = M_L_DQS_DP<4>
  VSS(17)  = GND
  DQ(39)  = M_L_DQ<38>
  VSS(16)  = GND
  DQ(35)  = M_L_DQ<34>
  VSS(15)  = GND
  DQ(45)  = M_L_DQ<44>
  VSS(14)  = GND
  DQ(41)  = M_L_DQ<40>
  VSS(13)  = GND
  DQS5N  = M_L_DQS_DN<5>
  DQS5P  = M_L_DQS_DP<5>
  VSS(12)  = GND
  DQ(47)  = M_L_DQ<46>
  VSS(11)  = GND
  DQ(43)  = M_L_DQ<42>
  VSS(10)  = GND
  DQ(53)  = M_L_DQ<52>
  VSS(9)  = GND
  DQ(49)  = M_L_DQ<48>
  VSS(8)  = GND
  DQS6N  = M_L_DQS_DN<6>
  DQS6P  = M_L_DQS_DP<6>
  VSS(7)  = GND
  DQ(55)  = M_L_DQ<54>
  VSS(6)  = GND
  DQ(51)  = M_L_DQ<50>
  VSS(5)  = GND
  DQ(61)  = M_L_DQ<60>
  VSS(4)  = GND
  DQ(57)  = M_L_DQ<56>
  VSS(3)  = GND
  DQS7N  = M_L_DQS_DN<7>
  DQS7P  = M_L_DQS_DP<7>
  VSS(2)  = GND
  DQ(63)  = M_L_DQ<62>
  VSS(1)  = GND
  DQ(59)  = M_L_DQ<58>
  VSS(0)  = GND
  VDDSPD  = PVPP_KLM
  SDA  = SMB_DDR_KLM_VPP_SDA
  VPP(1)  = PVPP_KLM
  VPP(0)  = PVPP_KLM
  VPP(2)  = PVPP_KLM

(kicad_pcb
	(version 20260206)
	(generator "pcbnew")
	(generator_version "10.0")
	(general
		(thickness 1.6)
		(legacy_teardrops no)
	)
	(paper "A4")
	(title_block
		(title "Wiwynn_Tioga_Pass_MB.brd")
		(comment 1 "Tioga Pass / footprint 2031 of 4770 (J1A2), pads 153-202 of 291")
	)
	(layers
		(0 "F.Cu" signal "TOP")
		(4 "In1.Cu" signal "L2GND")
		(6 "In2.Cu" signal "L3")
		(8 "In3.Cu" signal "L4GND")
		(10 "In4.Cu" signal "L5")
		(12 "In5.Cu" signal "L6GND")
		(14 "In6.Cu" signal "L7VCC")
		(16 "In7.Cu" signal "L8VCC")
		(18 "In8.Cu" signal "L9GND")
		(20 "In9.Cu" signal "L10")
		(22 "In10.Cu" signal "L11GND")
		(24 "In11.Cu" signal "L12")
		(26 "In12.Cu" signal "L13GND")
		(2 "B.Cu" signal "BOTTOM")
		(9 "F.Adhes" user "F.Adhesive")
		(11 "B.Adhes" user "B.Adhesive")
		(13 "F.Paste" user "Package Geometry/Pastemask Top")
		(15 "B.Paste" user "Package Geometry/Pastemask Bottom")
		(5 "F.SilkS" user "Ref Des/Silkscreen Top")
		(7 "B.SilkS" user "Ref Des/Silkscreen Bottom")
		(1 "F.Mask" user "Board Geometry/Soldermask Top")
		(3 "B.Mask" user "Board Geometry/Soldermask Bottom")
		(17 "Dwgs.User" user "User.Drawings")
		(19 "Cmts.User" user "User.Comments")
		(21 "Eco1.User" user "User.Eco1")
		(23 "Eco2.User" user "User.Eco2")
		(25 "Edge.Cuts" user "Board Geometry/Outline")
		(27 "Margin" user)
		(31 "F.CrtYd" user "Package Geometry/Place Bound Top")
		(29 "B.CrtYd" user "Package Geometry/Place Bound Bottom")
		(35 "F.Fab" user "Ref Des/Assembly Top")
		(33 "B.Fab" user "Ref Des/Assembly Bottom")
	)
	(footprint ""
		(layer "F.Cu")
		(at 29.699458 -142.6718 90)
		(property "Reference" "J1A2"
			(at -2.623312 42.436542 0)
			(unlocked yes)
			(layer "F.SilkS")
			(effects
				(font
					(size 0.7874 0.5842)
					(thickness 0.1524)
				)
				(justify left)
			)
		)
		(property "Value" ""
			(at 0 0 90)
			(layer "F.Fab")
			(effects
				(font
					(size 1.27 1.27)
				)
			)
		)
		(duplicate_pad_numbers_are_jumpers no)
		(pad "150" smd rect
			(at 4.59994 4.249928 90)
			(size 1.8034 0.508)
			(layers "F.Cu" "F.Mask" "F.Paste")
			(net "M_L_DQ<0>")
		)
		(pad "151" smd rect
			(at 4.59994 5.100066 90)
			(size 1.8034 0.508)
			(layers "F.Cu" "F.Mask" "F.Paste")
			(net "GND")
		)
		(pad "152" smd rect
			(at 4.59994 5.94995 90)
			(size 1.8034 0.508)
			(layers "F.Cu" "F.Mask" "F.Paste")
			(net "M_L_DQS_DN<0>")
		)
		(pad "153" smd rect
			(at 4.59994 6.800088 90)
			(size 1.8034 0.508)
			(layers "F.Cu" "F.Mask" "F.Paste")
			(net "M_L_DQS_DP<0>")
		)
		(pad "154" smd rect
			(at 4.59994 7.649972 90)
			(size 1.8034 0.508)
			(layers "F.Cu" "F.Mask" "F.Paste")
			(net "GND")
		)
		(pad "155" smd rect
			(at 4.59994 8.50011 90)
			(size 1.8034 0.508)
			(layers "F.Cu" "F.Mask" "F.Paste")
			(net "M_L_DQ<6>")
		)
		(pad "156" smd rect
			(at 4.59994 9.349994 90)
			(size 1.8034 0.508)
			(layers "F.Cu" "F.Mask" "F.Paste")
			(net "GND")
		)
		(pad "157" smd rect
			(at 4.59994 10.199878 90)
			(size 1.8034 0.508)
			(layers "F.Cu" "F.Mask" "F.Paste")
			(net "M_L_DQ<2>")
		)
		(pad "158" smd rect
			(at 4.59994 11.050016 90)
			(size 1.8034 0.508)
			(layers "F.Cu" "F.Mask" "F.Paste")
			(net "GND")
		)
		(pad "159" smd rect
			(at 4.59994 11.8999 90)
			(size 1.8034 0.508)
			(layers "F.Cu" "F.Mask" "F.Paste")
			(net "M_L_DQ<12>")
		)
		(pad "160" smd rect
			(at 4.59994 12.750038 90)
			(size 1.8034 0.508)
			(layers "F.Cu" "F.Mask" "F.Paste")
			(net "GND")
		)
		(pad "161" smd rect
			(at 4.59994 13.599922 90)
			(size 1.8034 0.508)
			(layers "F.Cu" "F.Mask" "F.Paste")
			(net "M_L_DQ<8>")
		)
		(pad "162" smd rect
			(at 4.59994 14.45006 90)
			(size 1.8034 0.508)
			(layers "F.Cu" "F.Mask" "F.Paste")
			(net "GND")
		)
		(pad "163" smd rect
			(at 4.59994 15.299944 90)
			(size 1.8034 0.508)
			(layers "F.Cu" "F.Mask" "F.Paste")
			(net "M_L_DQS_DN<1>")
		)
		(pad "164" smd rect
			(at 4.59994 16.150082 90)
			(size 1.8034 0.508)
			(layers "F.Cu" "F.Mask" "F.Paste")
			(net "M_L_DQS_DP<1>")
		)
		(pad "165" smd rect
			(at 4.59994 16.999966 90)
			(size 1.8034 0.508)
			(layers "F.Cu" "F.Mask" "F.Paste")
			(net "GND")
		)
		(pad "166" smd rect
			(at 4.59994 17.850104 90)
			(size 1.8034 0.508)
			(layers "F.Cu" "F.Mask" "F.Paste")
			(net "M_L_DQ<14>")
		)
		(pad "167" smd rect
			(at 4.59994 18.699988 90)
			(size 1.8034 0.508)
			(layers "F.Cu" "F.Mask" "F.Paste")
			(net "GND")
		)
		(pad "168" smd rect
			(at 4.59994 19.550126 90)
			(size 1.8034 0.508)
			(layers "F.Cu" "F.Mask" "F.Paste")
			(net "M_L_DQ<10>")
		)
		(pad "169" smd rect
			(at 4.59994 20.40001 90)
			(size 1.8034 0.508)
			(layers "F.Cu" "F.Mask" "F.Paste")
			(net "GND")
		)
		(pad "170" smd rect
			(at 4.59994 21.249894 90)
			(size 1.8034 0.508)
			(layers "F.Cu" "F.Mask" "F.Paste")
			(net "M_L_DQ<20>")
		)
		(pad "171" smd rect
			(at 4.59994 22.100032 90)
			(size 1.8034 0.508)
			(layers "F.Cu" "F.Mask" "F.Paste")
			(net "GND")
		)
		(pad "172" smd rect
			(at 4.59994 22.949916 90)
			(size 1.8034 0.508)
			(layers "F.Cu" "F.Mask" "F.Paste")
			(net "M_L_DQ<16>")
		)
		(pad "173" smd rect
			(at 4.59994 23.800054 90)
			(size 1.8034 0.508)
			(layers "F.Cu" "F.Mask" "F.Paste")
			(net "GND")
		)
		(pad "174" smd rect
			(at 4.59994 24.649938 90)
			(size 1.8034 0.508)
			(layers "F.Cu" "F.Mask" "F.Paste")
			(net "M_L_DQS_DN<2>")
		)
		(pad "175" smd rect
			(at 4.59994 25.500076 90)
			(size 1.8034 0.508)
			(layers "F.Cu" "F.Mask" "F.Paste")
			(net "M_L_DQS_DP<2>")
		)
		(pad "176" smd rect
			(at 4.59994 26.34996 90)
			(size 1.8034 0.508)
			(layers "F.Cu" "F.Mask" "F.Paste")
			(net "GND")
		)
		(pad "177" smd rect
			(at 4.59994 27.200098 90)
			(size 1.8034 0.508)
			(layers "F.Cu" "F.Mask" "F.Paste")
			(net "M_L_DQ<22>")
		)
		(pad "178" smd rect
			(at 4.59994 28.049982 90)
			(size 1.8034 0.508)
			(layers "F.Cu" "F.Mask" "F.Paste")
			(net "GND")
		)
		(pad "179" smd rect
			(at 4.59994 28.90012 90)
			(size 1.8034 0.508)
			(layers "F.Cu" "F.Mask" "F.Paste")
			(net "M_L_DQ<18>")
		)
		(pad "180" smd rect
			(at 4.59994 29.750004 90)
			(size 1.8034 0.508)
			(layers "F.Cu" "F.Mask" "F.Paste")
			(net "GND")
		)
		(pad "181" smd rect
			(at 4.59994 30.599888 90)
			(size 1.8034 0.508)
			(layers "F.Cu" "F.Mask" "F.Paste")
			(net "M_L_DQ<28>")
		)
		(pad "182" smd rect
			(at 4.59994 31.450026 90)
			(size 1.8034 0.508)
			(layers "F.Cu" "F.Mask" "F.Paste")
			(net "GND")
		)
		(pad "183" smd rect
			(at 4.59994 32.29991 90)
			(size 1.8034 0.508)
			(layers "F.Cu" "F.Mask" "F.Paste")
			(net "M_L_DQ<24>")
		)
		(pad "184" smd rect
			(at 4.59994 33.150048 90)
			(size 1.8034 0.508)
			(layers "F.Cu" "F.Mask" "F.Paste")
			(net "GND")
		)
		(pad "185" smd rect
			(at 4.59994 33.999932 90)
			(size 1.8034 0.508)
			(layers "F.Cu" "F.Mask" "F.Paste")
			(net "M_L_DQS_DN<3>")
		)
		(pad "186" smd rect
			(at 4.59994 34.85007 90)
			(size 1.8034 0.508)
			(layers "F.Cu" "F.Mask" "F.Paste")
			(net "M_L_DQS_DP<3>")
		)
		(pad "187" smd rect
			(at 4.59994 35.699954 90)
			(size 1.8034 0.508)
			(layers "F.Cu" "F.Mask" "F.Paste")
			(net "GND")
		)
		(pad "188" smd rect
			(at 4.59994 36.550092 90)
			(size 1.8034 0.508)
			(layers "F.Cu" "F.Mask" "F.Paste")
			(net "M_L_DQ<30>")
		)
		(pad "189" smd rect
			(at 4.59994 37.399976 90)
			(size 1.8034 0.508)
			(layers "F.Cu" "F.Mask" "F.Paste")
			(net "GND")
		)
		(pad "190" smd rect
			(at 4.59994 38.250114 90)
			(size 1.8034 0.508)
			(layers "F.Cu" "F.Mask" "F.Paste")
			(net "M_L_DQ<26>")
		)
		(pad "191" smd rect
			(at 4.59994 39.099998 90)
			(size 1.8034 0.508)
			(layers "F.Cu" "F.Mask" "F.Paste")
			(net "GND")
		)
		(pad "192" smd rect
			(at 4.59994 39.949882 90)
			(size 1.8034 0.508)
			(layers "F.Cu" "F.Mask" "F.Paste")
			(net "M_L_ECC<4>")
		)
		(pad "193" smd rect
			(at 4.59994 40.80002 90)
			(size 1.8034 0.508)
			(layers "F.Cu" "F.Mask" "F.Paste")
			(net "GND")
		)
		(pad "194" smd rect
			(at 4.59994 41.649904 90)
			(size 1.8034 0.508)
			(layers "F.Cu" "F.Mask" "F.Paste")
			(net "M_L_ECC<0>")
		)
		(pad "195" smd rect
			(at 4.59994 42.500042 90)
			(size 1.8034 0.508)
			(layers "F.Cu" "F.Mask" "F.Paste")
			(net "GND")
		)
		(pad "196" smd rect
			(at 4.59994 43.349926 90)
			(size 1.8034 0.508)
			(layers "F.Cu" "F.Mask" "F.Paste")
			(net "M_L_DQS_DN<8>")
		)
		(pad "197" smd rect
			(at 4.59994 44.200064 90)
			(size 1.8034 0.508)
			(layers "F.Cu" "F.Mask" "F.Paste")
			(net "M_L_DQS_DP<8>")
		)
		(pad "198" smd rect
			(at 4.59994 45.049948 90)
			(size 1.8034 0.508)
			(layers "F.Cu" "F.Mask" "F.Paste")
			(net "GND")
		)
		(pad "199" smd rect
			(at 4.59994 45.900086 90)
			(size 1.8034 0.508)
			(layers "F.Cu" "F.Mask" "F.Paste")
			(net "M_L_ECC<6>")
		)
	)
)
